# S9S_MB_2U (Grand Teton) — schematic netlist excerpt (pin names and nets, part order shuffled) for the footprints in the layout excerpt that follows; sources: Cadence DE-HDL packaged netlist, KiCad conversion of 03242023_DA0F0TMBIJ0_F0T_Motherboard_J_brd_V01_OCP.brd

R4185  Q_RES  1K 1% CHIP  pkg 0402LF  page 170 : A = U273_3_ADD2 ; B = GND

PPQ5  MOSFET_NCH_1D3S  PSMNR58-30YLH EMPTY  pkg SOT1023  page 304
  \1\  = P12V_AUX
  \2\  = P12V_AUX
  \3\  = P12V_AUX
  \4\  = P12V_HSC_GATE_G1
  \5\  = P12V_MAIN_R

(kicad_pcb
	(version 20260206)
	(generator "pcbnew")
	(generator_version "10.0")
	(general
		(thickness 1.6)
		(legacy_teardrops no)
	)
	(paper "A4")
	(title_block
		(title "03242023_DA0F0TMBIJ0_F0T_Motherboard_J_brd_V01_OCP.brd")
		(comment 1 "Grand Teton / footprints 1071-1072 of 6105")
	)
	(layers
		(0 "F.Cu" signal "TOP")
		(4 "In1.Cu" signal "GND")
		(6 "In2.Cu" signal "IN1")
		(8 "In3.Cu" signal "GND1")
		(10 "In4.Cu" signal "IN2")
		(12 "In5.Cu" signal "GND2")
		(14 "In6.Cu" signal "IN3")
		(16 "In7.Cu" signal "GND3")
		(18 "In8.Cu" signal "VCC")
		(20 "In9.Cu" signal "VCC1")
		(22 "In10.Cu" signal "GND4")
		(24 "In11.Cu" signal "IN4")
		(26 "In12.Cu" signal "GND5")
		(28 "In13.Cu" signal "IN5")
		(30 "In14.Cu" signal "GND6")
		(32 "In15.Cu" signal "IN6")
		(34 "In16.Cu" signal "GND7")
		(2 "B.Cu" signal "BOTTOM")
		(9 "F.Adhes" user "F.Adhesive")
		(11 "B.Adhes" user "B.Adhesive")
		(13 "F.Paste" user "Package Geometry/Pastemask Top")
		(15 "B.Paste" user "Package Geometry/Pastemask Bottom")
		(5 "F.SilkS" user "Ref Des/Silkscreen Top")
		(7 "B.SilkS" user "Ref Des/Silkscreen Bottom")
		(1 "F.Mask" user "Board Geometry/Soldermask Top")
		(3 "B.Mask" user "Board Geometry/Soldermask Bottom")
		(17 "Dwgs.User" user "User.Drawings")
		(19 "Cmts.User" user "User.Comments")
		(21 "Eco1.User" user "User.Eco1")
		(23 "Eco2.User" user "User.Eco2")
		(25 "Edge.Cuts" user "Board Geometry/Outline")
		(27 "Margin" user)
		(31 "F.CrtYd" user "Package Geometry/Place Bound Top")
		(29 "B.CrtYd" user "Package Geometry/Place Bound Bottom")
		(35 "F.Fab" user "Ref Des/Assembly Top")
		(33 "B.Fab" user "Ref Des/Assembly Bottom")
	)
	(footprint ""
		(layer "F.Cu")
		(at 254.161544 -398.78 90)
		(property "Reference" "PPQ5"
			(at -8.245856 -1.914144 0)
			(unlocked yes)
			(layer "F.SilkS")
			(effects
				(font
					(size 0.7874 0.5842)
					(thickness 0.1524)
				)
				(justify left)
			)
		)
		(property "Value" ""
			(at 0 0 90)
			(layer "F.Fab")
			(effects
				(font
					(size 1.27 1.27)
				)
			)
		)
		(duplicate_pad_numbers_are_jumpers no)
		(fp_line
			(start 2.350008 -2.649982)
			(end 2.350008 -2.4892)
			(stroke
				(width 0.1524)
				(type default)
			)
			(layer "F.SilkS")
		)
		(fp_line
			(start -2.350008 -2.649982)
			(end 2.350008 -2.649982)
			(stroke
				(width 0.1524)
				(type default)
			)
			(layer "F.SilkS")
		)
		(fp_line
			(start -2.350008 -2.4384)
			(end -2.350008 -2.649982)
			(stroke
				(width 0.1524)
				(type default)
			)
			(layer "F.SilkS")
		)
		(fp_line
			(start 2.350008 2.4892)
			(end 2.350008 2.649982)
			(stroke
				(width 0.1524)
				(type default)
			)
			(layer "F.SilkS")
		)
		(fp_line
			(start 2.350008 2.649982)
			(end -2.350008 2.649982)
			(stroke
				(width 0.1524)
				(type default)
			)
			(layer "F.SilkS")
		)
		(fp_line
			(start -2.350008 2.649982)
			(end -2.350008 2.413)
			(stroke
				(width 0.1524)
				(type default)
			)
			(layer "F.SilkS")
		)
		(fp_poly
			(pts
				(xy -3.717544 -1.905) (xy -4.758944 -2.3241) (xy -4.758944 -1.524)
			)
			(stroke
				(width 0)
				(type default)
			)
			(fill yes)
			(layer "F.SilkS")
		)
		(fp_line
			(start 2.350008 -2.649982)
			(end 2.350008 2.649982)
			(stroke
				(width 0.1)
				(type default)
			)
			(layer "F.Fab")
		)
		(fp_line
			(start -2.350008 -2.649982)
			(end 2.350008 -2.649982)
			(stroke
				(width 0.1)
				(type default)
			)
			(layer "F.Fab")
		)
		(fp_line
			(start 2.350008 2.649982)
			(end -2.350008 2.649982)
			(stroke
				(width 0.1)
				(type default)
			)
			(layer "F.Fab")
		)
		(fp_line
			(start -2.350008 2.649982)
			(end -2.350008 -2.649982)
			(stroke
				(width 0.1)
				(type default)
			)
			(layer "F.Fab")
		)
		(fp_poly
			(pts
				(xy -3.717544 -1.905) (xy -4.758944 -2.3241) (xy -4.758944 -1.524)
			)
			(stroke
				(width 0)
				(type default)
			)
			(fill yes)
			(layer "F.Fab")
		)
		(pad "1" smd rect
			(at -2.999994 -1.905)
			(size 0.7112 1.1684)
			(layers "F.Cu" "F.Mask" "F.Paste")
			(net "P12V_AUX")
		)
		(pad "2" smd rect
			(at -2.999994 -0.635)
			(size 0.7112 1.1684)
			(layers "F.Cu" "F.Mask" "F.Paste")
			(net "P12V_AUX")
		)
		(pad "3" smd rect
			(at -2.999994 0.635)
			(size 0.7112 1.1684)
			(layers "F.Cu" "F.Mask" "F.Paste")
			(net "P12V_AUX")
		)
		(pad "4" smd rect
			(at -2.999994 1.905)
			(size 0.7112 1.1684)
			(layers "F.Cu" "F.Mask" "F.Paste")
			(net "P12V_HSC_GATE_G1")
		)
		(pad "5" smd circle
			(at 0.925068 0)
			(size 0 0)
			(layers "F.Cu" "F.Mask" "F.Paste")
			(net "P12V_MAIN_R")
		)
		(zone
			(layer "F.Cu")
			(hatch none 0.5)
			(connect_pads
				(clearance 0)
			)
			(min_thickness 0.25)
			(keepout
				(tracks not_allowed)
				(vias allowed)
				(pads allowed)
				(copperpour not_allowed)
				(footprints allowed)
			)
			(placement
				(enabled no)
				(sheetname "")
			)
			(fill
				(thermal_gap 0.5)
				(thermal_bridge_width 0.5)
				(island_removal_mode 0)
			)
			(polygon
				(pts
					(xy 252.002544 -397.3322) (xy 256.320544 -397.3322) (xy 256.320544 -397.33982) (xy 256.803144 -397.33982)
					(xy 256.803144 -396.4305) (xy 251.519944 -396.4305) (xy 251.519944 -397.3322)
				)
			)
		)
	)
	(footprint ""
		(layer "F.Cu")
		(at 120.315482 -14.20749)
		(property "Reference" "R4185"
			(at 0 0 0)
			(layer "F.SilkS")
			(hide yes)
			(effects
				(font
					(size 1.27 1.27)
				)
			)
		)
		(property "Value" ""
			(at 0 0 0)
			(layer "F.Fab")
			(effects
				(font
					(size 1.27 1.27)
				)
			)
		)
		(duplicate_pad_numbers_are_jumpers no)
		(fp_line
			(start -0.7874 -0.4064)
			(end 0.7874 -0.4064)
			(stroke
				(width 0.1524)
				(type default)
			)
			(layer "F.SilkS")
		)
		(fp_line
			(start -0.7874 0.4064)
			(end -0.7874 -0.4064)
			(stroke
				(width 0.1524)
				(type default)
			)
			(layer "F.SilkS")
		)
		(fp_line
			(start 0.7874 -0.4064)
			(end 0.7874 0.4064)
			(stroke
				(width 0.1524)
				(type default)
			)
			(layer "F.SilkS")
		)
		(fp_line
			(start 0.7874 0.4064)
			(end -0.7874 0.4064)
			(stroke
				(width 0.1524)
				(type default)
			)
			(layer "F.SilkS")
		)
		(fp_line
			(start -0.67945 -0.305054)
			(end -0.12065 -0.305054)
			(stroke
				(width 0.1)
				(type default)
			)
			(layer "F.Fab")
		)
		(fp_line
			(start -0.67945 0.3048)
			(end -0.67945 -0.305054)
			(stroke
				(width 0.1)
				(type default)
			)
			(layer "F.Fab")
		)
		(fp_line
			(start -0.12065 -0.305054)
			(end -0.12065 -0.2794)
			(stroke
				(width 0.1)
				(type default)
			)
			(layer "F.Fab")
		)
		(fp_line
			(start -0.12065 -0.2794)
			(end 0.12065 -0.2794)
			(stroke
				(width 0.1)
				(type default)
			)
			(layer "F.Fab")
		)
		(fp_line
			(start -0.12065 0.2794)
			(end -0.12065 0.3048)
			(stroke
				(width 0.1)
				(type default)
			)
			(layer "F.Fab")
		)
		(fp_line
			(start -0.12065 0.3048)
			(end -0.67945 0.3048)
			(stroke
				(width 0.1)
				(type default)
			)
			(layer "F.Fab")
		)
		(fp_line
			(start 0.120396 0.2794)
			(end -0.12065 0.2794)
			(stroke
				(width 0.1)
				(type default)
			)
			(layer "F.Fab")
		)
		(fp_line
			(start 0.120396 0.3048)
			(end 0.120396 0.2794)
			(stroke
				(width 0.1)
				(type default)
			)
			(layer "F.Fab")
		)
		(fp_line
			(start 0.12065 -0.3048)
			(end 0.67945 -0.3048)
			(stroke
				(width 0.1)
				(type default)
			)
			(layer "F.Fab")
		)
		(fp_line
			(start 0.12065 -0.2794)
			(end 0.12065 -0.3048)
			(stroke
				(width 0.1)
				(type default)
			)
			(layer "F.Fab")
		)
		(fp_line
			(start 0.67945 -0.3048)
			(end 0.67945 0.3048)
			(stroke
				(width 0.1)
				(type default)
			)
			(layer "F.Fab")
		)
		(fp_line
			(start 0.67945 0.3048)
			(end 0.120396 0.3048)
			(stroke
				(width 0.1)
				(type default)
			)
			(layer "F.Fab")
		)
		(pad "1" smd circle
			(at -0.40005 0)
			(size 0 0)
			(layers "F.Cu" "F.Mask" "F.Paste")
			(net "U273_3_ADD2")
		)
		(pad "2" smd circle
			(at 0.40005 0)
			(size 0 0)
			(layers "F.Cu" "F.Mask" "F.Paste")
			(net "GND")
		)
	)
)
